FILE_TYPE = CONNECTIVITY;
{Allegro Design Entry HDL 17.2-2016 S081 (4005846) 1/11/2022}
"PAGE_NUMBER" = 80;
0"NC";
1"P3V3_AUX\g";
2"PVNN_MAIN_CPU0\g";
3"PVNN_MAIN_CPU0\g";
4"PVCCINFAON_CPU0\g";
5"P3V3_AUX\g";
6"PVNN_MAIN_CPU1\g";
7"PVNN_TERM_CPU0\g";
8"PVNN_MAIN_CPU1\g";
9"PVCCINFAON_CPU1\g";
10"PVNN_TERM_CPU1\g";
11"GND\g";
12"GND\g";
13"PU_S3M_CPU1_CPLD_STATUS";
14"PU_S3M_CPU1_CPLD_CONFD";
15"FM_S3M_CPU1_CPLD_CONFIG_N";
16"FM_S3M_CPU1_CPLD_CRC_ERROR";
17"FM_S3M_CPU0_CPLD_CRC_ERROR";
18"PU_S3M_CPU0_CPLD_STATUS";
19"PU_S3M_CPU0_CPLD_CONFD";
20"FM_S3M_CPU0_CPLD_CONFIG_N";
%"Q_RES"
"1","(-2375,-1225)","0","pure_quanta","I1";
;
PART_NUMBER"CS21502FB07"
PACK_TYPE"0402LF"
TOLERANCE"1%"
VALUE"1.5K"
MATERIAL"CHIP"
WATTAGE"1/16W"
$LOCATION"R1216"
CDS_LIB"pure_quanta"
CDS_LOCATION"R1216"
$SEC"1"
CDS_SEC"1";
"B"
$PN"2"17;
"A"
$PN"1"1;
%"UNIVERSAL_POWER"
"1","(-2725,2025)","0","logical_power","I10";
;
HDL_POWER"PVNN_MAIN_CPU0"
CDS_LIB"logical_power";
"A"3;
%"UNIVERSAL_POWER"
"1","(-2275,1925)","0","logical_power","I11";
;
HDL_POWER"PVCCINFAON_CPU0"
CDS_LIB"logical_power";
"A"4;
%"Q_RES"
"1","(-1800,1500)","0","pure_quanta","I12";
;
PART_NUMBER"CS00007T200"
TOLERANCE""
PACK_TYPE"1206LF"
MATERIAL"CHIP"
VALUE"0"
WATTAGE"1/2W"
$LOCATION"R324"
CDS_LIB"pure_quanta"
CDS_LOCATION"R324"
$SEC"1"
CDS_SEC"1";
"B"
$PN"2"7;
"A"
$PN"1"3;
%"Q_RES"
"1","(-1800,1750)","0","pure_quanta","I13";
;
PART_NUMBER"CS00007T200"
PACK_TYPE"1206LF"
VALUE"0"
TOLERANCE""
WATTAGE"1/2W"
MATERIAL"EMPTY"
$LOCATION"R323"
CDS_LIB"pure_quanta"
CDS_LOCATION"R323"
$SEC"1"
CDS_SEC"1";
"B"
$PN"2"7;
"A"
$PN"1"4;
%"UNIVERSAL_POWER"
"1","(425,-600)","0","logical_power","I18";
;
HDL_POWER"P3V3_AUX"
CDS_LIB"logical_power";
"A"5;
%"UNIVERSAL_GND"
"1","(400,375)","0","logical_power","I19";
;
CDS_LIB"logical_power"
HDL_POWER"GND";
"A"12;
%"Q_RES"
"1","(-2375,-1100)","0","pure_quanta","I2";
;
PART_NUMBER"CS31002FB08"
TOLERANCE"1%"
VALUE"10K"
MATERIAL"CHIP"
$LOCATION"R321"
WATTAGE"1/16W"
CDS_LIB"pure_quanta"
PACK_TYPE"0402LF"
CDS_LOCATION"R321"
$SEC"1"
CDS_SEC"1";
"B"
$PN"2"20;
"A"
$PN"1"1;
%"Q_CAP"
"1","(400,700)","0","pure_quanta","I20";
;
PART_NUMBER"CH622KMEB01"
VOLTAGE"4V"
PACK_TYPE"C0402"
VALUE"22UF"
MATERIAL"X6S"
TOLERANCE"20%"
$LOCATION"C1365"
CDS_LIB"pure_quanta"
CDS_LOCATION"C1365"
$SEC"1"
CDS_SEC"1";
"B"
$PN"2"12;
"A"
$PN"1"6;
%"UNIVERSAL_POWER"
"1","(400,975)","0","logical_power","I21";
;
HDL_POWER"PVNN_MAIN_CPU1"
CDS_LIB"logical_power";
"A"6;
%"Q_RES"
"1","(775,-1225)","0","pure_quanta","I22";
;
PART_NUMBER"CS21502FB07"
PACK_TYPE"0402LF"
MATERIAL"CHIP"
WATTAGE"1/16W"
TOLERANCE"1%"
VALUE"1.5K"
$LOCATION"R1217"
CDS_LIB"pure_quanta"
CDS_LOCATION"R1217"
$SEC"1"
CDS_SEC"1";
"B"
$PN"2"16;
"A"
$PN"1"5;
%"Q_RES"
"1","(775,-1100)","0","pure_quanta","I25";
;
PART_NUMBER"CS31002FB08"
VALUE"10K"
TOLERANCE"1%"
MATERIAL"CHIP"
$LOCATION"R327"
CDS_LIB"pure_quanta"
WATTAGE"1/16W"
PACK_TYPE"0402LF"
CDS_LOCATION"R327"
$SEC"1"
CDS_SEC"1";
"B"
$PN"2"15;
"A"
$PN"1"5;
%"Q_RES"
"1","(775,-975)","0","pure_quanta","I26";
;
PART_NUMBER"CS31002FB08"
TOLERANCE"1%"
MATERIAL"CHIP"
VALUE"10K"
$LOCATION"R326"
CDS_LIB"pure_quanta"
WATTAGE"1/16W"
PACK_TYPE"0402LF"
CDS_LOCATION"R326"
$SEC"1"
CDS_SEC"1";
"B"
$PN"2"14;
"A"
$PN"1"5;
%"Q_RES"
"1","(775,-850)","0","pure_quanta","I27";
;
PART_NUMBER"CS31002FB08"
TOLERANCE"1%"
VALUE"10K"
PACK_TYPE"0402LF"
WATTAGE"1/16W"
MATERIAL"CHIP"
$LOCATION"R325"
CDS_LIB"pure_quanta"
CDS_LOCATION"R325"
$SEC"1"
CDS_SEC"1";
"B"
$PN"2"13;
"A"
$PN"1"5;
%"Q_CAP"
"1","(775,700)","0","pure_quanta","I28";
;
PART_NUMBER"CH622KMEB01"
VOLTAGE"4V"
MATERIAL"X6S"
TOLERANCE"20%"
PACK_TYPE"C0402"
VALUE"22UF"
$LOCATION"C1366"
CDS_LIB"pure_quanta"
CDS_LOCATION"C1366"
$SEC"1"
CDS_SEC"1";
"B"
$PN"2"12;
"A"
$PN"1"6;
%"UNIVERSAL_POWER"
"1","(-2725,-600)","0","logical_power","I3";
;
HDL_POWER"P3V3_AUX"
CDS_LIB"logical_power";
"A"1;
%"UNIVERSAL_POWER"
"1","(-1175,2025)","0","logical_power","I31";
;
HDL_POWER"PVNN_TERM_CPU0"
CDS_LIB"logical_power";
"A"7;
%"UNIVERSAL_POWER"
"1","(425,2025)","0","logical_power","I32";
;
HDL_POWER"PVNN_MAIN_CPU1"
CDS_LIB"logical_power";
"A"8;
%"UNIVERSAL_POWER"
"1","(875,1925)","0","logical_power","I33";
;
HDL_POWER"PVCCINFAON_CPU1"
CDS_LIB"logical_power";
"A"9;
%"Q_RES"
"1","(1350,1500)","0","pure_quanta","I34";
;
PART_NUMBER"CS00007T200"
TOLERANCE""
VALUE"0"
MATERIAL"CHIP"
WATTAGE"1/2W"
PACK_TYPE"1206LF"
$LOCATION"R330"
CDS_LIB"pure_quanta"
CDS_LOCATION"R330"
$SEC"1"
CDS_SEC"1";
"B"
$PN"2"10;
"A"
$PN"1"8;
%"Q_RES"
"1","(1350,1750)","0","pure_quanta","I35";
;
PART_NUMBER"CS00007T200"
PACK_TYPE"1206LF"
VALUE"0"
TOLERANCE""
WATTAGE"1/2W"
MATERIAL"EMPTY"
$LOCATION"R329"
CDS_LIB"pure_quanta"
CDS_LOCATION"R329"
$SEC"1"
CDS_SEC"1";
"B"
$PN"2"10;
"A"
$PN"1"9;
%"UNIVERSAL_POWER"
"1","(1975,2025)","0","logical_power","I36";
;
HDL_POWER"PVNN_TERM_CPU1"
CDS_LIB"logical_power";
"A"10;
%"UNIVERSAL_GND"
"1","(-2750,375)","0","logical_power","I4";
;
CDS_LIB"logical_power"
HDL_POWER"GND";
"A"11;
%"Q_CAP"
"1","(-2750,700)","0","pure_quanta","I5";
;
PART_NUMBER"CH622KMEB01"
VOLTAGE"4V"
TOLERANCE"20%"
MATERIAL"X6S"
VALUE"22UF"
PACK_TYPE"C0402"
$LOCATION"C1363"
CDS_LIB"pure_quanta"
CDS_LOCATION"C1363"
$SEC"1"
CDS_SEC"1";
"B"
$PN"2"11;
"A"
$PN"1"2;
%"UNIVERSAL_POWER"
"1","(-2750,975)","0","logical_power","I6";
;
HDL_POWER"PVNN_MAIN_CPU0"
CDS_LIB"logical_power";
"A"2;
%"Q_RES"
"1","(-2375,-975)","0","pure_quanta","I7";
;
PART_NUMBER"CS31002FB08"
TOLERANCE"1%"
VALUE"10K"
MATERIAL"CHIP"
$LOCATION"R320"
CDS_LIB"pure_quanta"
WATTAGE"1/16W"
PACK_TYPE"0402LF"
CDS_LOCATION"R320"
$SEC"1"
CDS_SEC"1";
"B"
$PN"2"19;
"A"
$PN"1"1;
%"Q_RES"
"1","(-2375,-850)","0","pure_quanta","I8";
;
PART_NUMBER"CS31002FB08"
TOLERANCE"1%"
VALUE"10K"
PACK_TYPE"0402LF"
WATTAGE"1/16W"
MATERIAL"CHIP"
$LOCATION"R319"
CDS_LIB"pure_quanta"
CDS_LOCATION"R319"
$SEC"1"
CDS_SEC"1";
"B"
$PN"2"18;
"A"
$PN"1"1;
%"Q_CAP"
"1","(-2375,700)","0","pure_quanta","I9";
;
PART_NUMBER"CH622KMEB01"
VOLTAGE"4V"
PACK_TYPE"C0402"
TOLERANCE"20%"
VALUE"22UF"
MATERIAL"X6S"
$LOCATION"C1364"
CDS_LIB"pure_quanta"
CDS_LOCATION"C1364"
$SEC"1"
CDS_SEC"1";
"B"
$PN"2"11;
"A"
$PN"1"2;
END.
